(kicad_pcb
	(version 20260206)
	(generator "pcbnew")
	(generator_version "10.0")
	(general
		(thickness 1.6)
		(legacy_teardrops no)
	)
	(paper "A4")
	(title_block
		(title "04192023_DAF0TMB3IC0_F0TG_MB_C_brd_V02_OCP.brd")
		(comment 1 "Grand Teton / footprints 5547-5552 of 8354")
	)
	(layers
		(0 "F.Cu" signal "TOP")
		(4 "In1.Cu" signal "GND")
		(6 "In2.Cu" signal "IN1")
		(8 "In3.Cu" signal "GND1")
		(10 "In4.Cu" signal "IN2")
		(12 "In5.Cu" signal "GND2")
		(14 "In6.Cu" signal "IN3")
		(16 "In7.Cu" signal "GND3")
		(18 "In8.Cu" signal "VCC")
		(20 "In9.Cu" signal "VCC1")
		(22 "In10.Cu" signal "GND4")
		(24 "In11.Cu" signal "IN4")
		(26 "In12.Cu" signal "GND5")
		(28 "In13.Cu" signal "IN5")
		(30 "In14.Cu" signal "GND6")
		(32 "In15.Cu" signal "IN6")
		(34 "In16.Cu" signal "GND7")
		(2 "B.Cu" signal "BOTTOM")
		(9 "F.Adhes" user "F.Adhesive")
		(11 "B.Adhes" user "B.Adhesive")
		(13 "F.Paste" user "Package Geometry/Pastemask Top")
		(15 "B.Paste" user "Package Geometry/Pastemask Bottom")
		(5 "F.SilkS" user "Ref Des/Silkscreen Top")
		(7 "B.SilkS" user "Ref Des/Silkscreen Bottom")
		(1 "F.Mask" user "Board Geometry/Soldermask Top")
		(3 "B.Mask" user "Board Geometry/Soldermask Bottom")
		(17 "Dwgs.User" user "User.Drawings")
		(19 "Cmts.User" user "User.Comments")
		(21 "Eco1.User" user "User.Eco1")
		(23 "Eco2.User" user "User.Eco2")
		(25 "Edge.Cuts" user "Board Geometry/Outline")
		(27 "Margin" user)
		(31 "F.CrtYd" user "Package Geometry/Place Bound Top")
		(29 "B.CrtYd" user "Package Geometry/Place Bound Bottom")
		(35 "F.Fab" user "Ref Des/Assembly Top")
		(33 "B.Fab" user "Ref Des/Assembly Bottom")
	)
	(footprint ""
		(layer "B.Cu")
		(at 193.171318 -140.432536 90)
		(property "Reference" "R633"
			(at 0 0 90)
			(layer "B.SilkS")
			(hide yes)
			(effects
				(font
					(size 1.27 1.27)
				)
				(justify mirror)
			)
		)
		(property "Value" ""
			(at 0 0 90)
			(layer "B.Fab")
			(effects
				(font
					(size 1.27 1.27)
				)
				(justify mirror)
			)
		)
		(duplicate_pad_numbers_are_jumpers no)
		(fp_line
			(start 0.7874 -0.4064)
			(end -0.7874 -0.4064)
			(stroke
				(width 0.1524)
				(type default)
			)
			(layer "B.SilkS")
		)
		(fp_line
			(start -0.7874 -0.4064)
			(end -0.7874 0.4064)
			(stroke
				(width 0.1524)
				(type default)
			)
			(layer "B.SilkS")
		)
		(fp_line
			(start 0.7874 0.4064)
			(end 0.7874 -0.4064)
			(stroke
				(width 0.1524)
				(type default)
			)
			(layer "B.SilkS")
		)
		(fp_line
			(start -0.7874 0.4064)
			(end 0.7874 0.4064)
			(stroke
				(width 0.1524)
				(type default)
			)
			(layer "B.SilkS")
		)
		(fp_line
			(start 0.67945 -0.305054)
			(end 0.12065 -0.305054)
			(stroke
				(width 0.1)
				(type default)
			)
			(layer "B.Fab")
		)
		(fp_line
			(start 0.12065 -0.305054)
			(end 0.12065 -0.2794)
			(stroke
				(width 0.1)
				(type default)
			)
			(layer "B.Fab")
		)
		(fp_line
			(start -0.12065 -0.3048)
			(end -0.67945 -0.3048)
			(stroke
				(width 0.1)
				(type default)
			)
			(layer "B.Fab")
		)
		(fp_line
			(start -0.67945 -0.3048)
			(end -0.67945 0.3048)
			(stroke
				(width 0.1)
				(type default)
			)
			(layer "B.Fab")
		)
		(fp_line
			(start 0.12065 -0.2794)
			(end -0.12065 -0.2794)
			(stroke
				(width 0.1)
				(type default)
			)
			(layer "B.Fab")
		)
		(fp_line
			(start -0.12065 -0.2794)
			(end -0.12065 -0.3048)
			(stroke
				(width 0.1)
				(type default)
			)
			(layer "B.Fab")
		)
		(fp_line
			(start 0.12065 0.2794)
			(end 0.12065 0.3048)
			(stroke
				(width 0.1)
				(type default)
			)
			(layer "B.Fab")
		)
		(fp_line
			(start -0.120396 0.2794)
			(end 0.12065 0.2794)
			(stroke
				(width 0.1)
				(type default)
			)
			(layer "B.Fab")
		)
		(fp_line
			(start 0.67945 0.3048)
			(end 0.67945 -0.305054)
			(stroke
				(width 0.1)
				(type default)
			)
			(layer "B.Fab")
		)
		(fp_line
			(start 0.12065 0.3048)
			(end 0.67945 0.3048)
			(stroke
				(width 0.1)
				(type default)
			)
			(layer "B.Fab")
		)
		(fp_line
			(start -0.120396 0.3048)
			(end -0.120396 0.2794)
			(stroke
				(width 0.1)
				(type default)
			)
			(layer "B.Fab")
		)
		(fp_line
			(start -0.67945 0.3048)
			(end -0.120396 0.3048)
			(stroke
				(width 0.1)
				(type default)
			)
			(layer "B.Fab")
		)
		(pad "1" smd circle
			(at 0.40005 0 270)
			(size 0 0)
			(layers "B.Cu" "B.Mask" "B.Paste")
			(net "PVDD18_S5_P0")
		)
		(pad "2" smd circle
			(at -0.40005 0 270)
			(size 0 0)
			(layers "B.Cu" "B.Mask" "B.Paste")
			(net "SMB_CPU_5_SDA")
		)
	)
	(footprint ""
		(layer "B.Cu")
		(at 43.247564 -337.989672 -90)
		(property "Reference" "PC458_2"
			(at 0 0 90)
			(layer "B.SilkS")
			(hide yes)
			(effects
				(font
					(size 1.27 1.27)
				)
				(justify mirror)
			)
		)
		(property "Value" ""
			(at 0 0 90)
			(layer "B.Fab")
			(effects
				(font
					(size 1.27 1.27)
				)
				(justify mirror)
			)
		)
		(duplicate_pad_numbers_are_jumpers no)
		(fp_line
			(start -1.524 0.762)
			(end 1.524 0.762)
			(stroke
				(width 0.1524)
				(type default)
			)
			(layer "B.SilkS")
		)
		(fp_line
			(start 1.524 0.762)
			(end 1.524 -0.762)
			(stroke
				(width 0.1524)
				(type default)
			)
			(layer "B.SilkS")
		)
		(fp_line
			(start -1.524 -0.762)
			(end -1.524 0.762)
			(stroke
				(width 0.1524)
				(type default)
			)
			(layer "B.SilkS")
		)
		(fp_line
			(start 1.524 -0.762)
			(end -1.524 -0.762)
			(stroke
				(width 0.1524)
				(type default)
			)
			(layer "B.SilkS")
		)
		(fp_line
			(start -1.1049 0.724916)
			(end -1.1049 -0.724916)
			(stroke
				(width 0.1)
				(type default)
			)
			(layer "B.Fab")
		)
		(fp_line
			(start 1.1049 0.724916)
			(end -1.1049 0.724916)
			(stroke
				(width 0.1)
				(type default)
			)
			(layer "B.Fab")
		)
		(fp_line
			(start -1.1049 -0.724916)
			(end 1.1049 -0.724916)
			(stroke
				(width 0.1)
				(type default)
			)
			(layer "B.Fab")
		)
		(fp_line
			(start 1.1049 -0.724916)
			(end 1.1049 0.724916)
			(stroke
				(width 0.1)
				(type default)
			)
			(layer "B.Fab")
		)
		(pad "1" smd rect
			(at 0.889 0 270)
			(size 1.016 1.27)
			(layers "B.Cu" "B.Mask" "B.Paste")
			(net "PVDDIO_P1")
		)
		(pad "2" smd rect
			(at -0.889 0 270)
			(size 1.016 1.27)
			(layers "B.Cu" "B.Mask" "B.Paste")
			(net "GND")
		)
	)
	(footprint ""
		(layer "B.Cu")
		(at 14.097762 -192.362328 -90)
		(property "Reference" "R108"
			(at 0 0 90)
			(layer "B.SilkS")
			(hide yes)
			(effects
				(font
					(size 1.27 1.27)
				)
				(justify mirror)
			)
		)
		(property "Value" ""
			(at 0 0 90)
			(layer "B.Fab")
			(effects
				(font
					(size 1.27 1.27)
				)
				(justify mirror)
			)
		)
		(duplicate_pad_numbers_are_jumpers no)
		(fp_line
			(start -0.7874 0.4064)
			(end 0.7874 0.4064)
			(stroke
				(width 0.1524)
				(type default)
			)
			(layer "B.SilkS")
		)
		(fp_line
			(start 0.7874 0.4064)
			(end 0.7874 -0.4064)
			(stroke
				(width 0.1524)
				(type default)
			)
			(layer "B.SilkS")
		)
		(fp_line
			(start -0.7874 -0.4064)
			(end -0.7874 0.4064)
			(stroke
				(width 0.1524)
				(type default)
			)
			(layer "B.SilkS")
		)
		(fp_line
			(start 0.7874 -0.4064)
			(end -0.7874 -0.4064)
			(stroke
				(width 0.1524)
				(type default)
			)
			(layer "B.SilkS")
		)
		(fp_line
			(start -0.67945 0.3048)
			(end -0.120396 0.3048)
			(stroke
				(width 0.1)
				(type default)
			)
			(layer "B.Fab")
		)
		(fp_line
			(start -0.120396 0.3048)
			(end -0.120396 0.2794)
			(stroke
				(width 0.1)
				(type default)
			)
			(layer "B.Fab")
		)
		(fp_line
			(start 0.12065 0.3048)
			(end 0.67945 0.3048)
			(stroke
				(width 0.1)
				(type default)
			)
			(layer "B.Fab")
		)
		(fp_line
			(start 0.67945 0.3048)
			(end 0.67945 -0.305054)
			(stroke
				(width 0.1)
				(type default)
			)
			(layer "B.Fab")
		)
		(fp_line
			(start -0.120396 0.2794)
			(end 0.12065 0.2794)
			(stroke
				(width 0.1)
				(type default)
			)
			(layer "B.Fab")
		)
		(fp_line
			(start 0.12065 0.2794)
			(end 0.12065 0.3048)
			(stroke
				(width 0.1)
				(type default)
			)
			(layer "B.Fab")
		)
		(fp_line
			(start -0.12065 -0.2794)
			(end -0.12065 -0.3048)
			(stroke
				(width 0.1)
				(type default)
			)
			(layer "B.Fab")
		)
		(fp_line
			(start 0.12065 -0.2794)
			(end -0.12065 -0.2794)
			(stroke
				(width 0.1)
				(type default)
			)
			(layer "B.Fab")
		)
		(fp_line
			(start -0.67945 -0.3048)
			(end -0.67945 0.3048)
			(stroke
				(width 0.1)
				(type default)
			)
			(layer "B.Fab")
		)
		(fp_line
			(start -0.12065 -0.3048)
			(end -0.67945 -0.3048)
			(stroke
				(width 0.1)
				(type default)
			)
			(layer "B.Fab")
		)
		(fp_line
			(start 0.12065 -0.305054)
			(end 0.12065 -0.2794)
			(stroke
				(width 0.1)
				(type default)
			)
			(layer "B.Fab")
		)
		(fp_line
			(start 0.67945 -0.305054)
			(end 0.12065 -0.305054)
			(stroke
				(width 0.1)
				(type default)
			)
			(layer "B.Fab")
		)
		(pad "1" smd circle
			(at 0.40005 0 90)
			(size 0 0)
			(layers "B.Cu" "B.Mask" "B.Paste")
			(net "P3V3")
		)
		(pad "2" smd circle
			(at -0.40005 0 90)
			(size 0 0)
			(layers "B.Cu" "B.Mask" "B.Paste")
			(net "PWRGD_CHF_CPU1_DIMM")
		)
	)
	(footprint ""
		(layer "B.Cu")
		(at 517.258808 -142.892526 -90)
		(property "Reference" "X8011"
			(at 4.4577 -1.50495 270)
			(unlocked yes)
			(layer "B.SilkS")
			(effects
				(font
					(size 0.7874 0.5842)
					(thickness 0.1524)
				)
				(justify left mirror)
			)
		)
		(property "Value" ""
			(at 0 0 90)
			(layer "B.Fab")
			(effects
				(font
					(size 1.27 1.27)
				)
				(justify mirror)
			)
		)
		(property "Device Type" "TP_TDR_4P_FTS_TH-TP_TDR_4P_DIP,EMPTY,TP15"
			(at -1.30175 1.27 180)
			(unlocked yes)
			(layer "B.Fab")
			(hide yes)
			(effects
				(font
					(size 0.635 0.4064)
					(thickness 0.1524)
				)
				(justify mirror)
			)
		)
		(property "User Part Number" "N_A"
			(at -1.30175 1.27 180)
			(unlocked yes)
			(layer "Cmts.User")
			(hide yes)
			(effects
				(font
					(size 0.635 0.4064)
					(thickness 0.1524)
				)
				(justify mirror)
			)
		)
		(duplicate_pad_numbers_are_jumpers no)
		(fp_line
			(start -2.54 3.81)
			(end -2.54 3.6703)
			(stroke
				(width 0.1524)
				(type default)
			)
			(layer "B.SilkS")
		)
		(fp_line
			(start 0 3.81)
			(end -2.54 3.81)
			(stroke
				(width 0.1524)
				(type default)
			)
			(layer "B.SilkS")
		)
		(fp_line
			(start 0 3.175)
			(end 0 3.81)
			(stroke
				(width 0.1524)
				(type default)
			)
			(layer "B.SilkS")
		)
		(fp_line
			(start -2.54 1.4097)
			(end -2.54 1.1303)
			(stroke
				(width 0.1524)
				(type default)
			)
			(layer "B.SilkS")
		)
		(fp_line
			(start 0 0.635)
			(end 0 1.905)
			(stroke
				(width 0.1524)
				(type default)
			)
			(layer "B.SilkS")
		)
		(fp_line
			(start -2.54 -1.1303)
			(end -2.54 -1.27)
			(stroke
				(width 0.1524)
				(type default)
			)
			(layer "B.SilkS")
		)
		(fp_line
			(start -2.54 -1.27)
			(end 0 -1.27)
			(stroke
				(width 0.1524)
				(type default)
			)
			(layer "B.SilkS")
		)
		(fp_line
			(start 0 -1.27)
			(end 0 -0.635)
			(stroke
				(width 0.1524)
				(type default)
			)
			(layer "B.SilkS")
		)
		(fp_poly
			(pts
				(xy 0.761746 0) (xy 2.285746 -0.762) (xy 2.285746 0.762)
			)
			(stroke
				(width 0)
				(type default)
			)
			(fill yes)
			(layer "B.SilkS")
		)
		(fp_line
			(start -2.54 3.81)
			(end -2.54 -1.27)
			(stroke
				(width 0.1)
				(type default)
			)
			(layer "B.Fab")
		)
		(fp_line
			(start 0 3.81)
			(end -2.54 3.81)
			(stroke
				(width 0.1)
				(type default)
			)
			(layer "B.Fab")
		)
		(fp_line
			(start -2.54 -1.27)
			(end 0 -1.27)
			(stroke
				(width 0.1)
				(type default)
			)
			(layer "B.Fab")
		)
		(fp_line
			(start 0 -1.27)
			(end 0 3.81)
			(stroke
				(width 0.1)
				(type default)
			)
			(layer "B.Fab")
		)
		(fp_poly
			(pts
				(xy 0.761746 0) (xy 2.285746 -0.762) (xy 2.285746 0.762)
			)
			(stroke
				(width 0)
				(type default)
			)
			(fill yes)
			(layer "B.Fab")
		)
		(pad "1" thru_hole circle
			(at 0 0 90)
			(size 1.0033 1.0033)
			(drill 0.249936)
			(layers "*.Cu" "*.Mask")
			(remove_unused_layers no)
			(net "TDR_DIFF_85_IN4_DN")
			(clearance 0.10795)
			(padstack
				(mode front_inner_back)
				(layer "Inner"
					(shape circle)
					(size 0.8001 0.8001)
					(clearance 0.1524)
				)
				(layer "B.Cu"
					(shape circle)
					(size 1.0033 1.0033)
					(thermal_gap 0.10795)
					(clearance 0.10795)
				)
			)
		)
		(pad "2" thru_hole circle
			(at -2.54 0 90)
			(size 1.9939 1.9939)
			(drill 0.249936)
			(layers "*.Cu" "*.Mask")
			(remove_unused_layers no)
			(net "T1_GND")
			(clearance 0.10795)
			(padstack
				(mode front_inner_back)
				(layer "Inner"
					(shape circle)
					(size 0.8001 0.8001)
					(clearance 0.1524)
				)
				(layer "B.Cu"
					(shape circle)
					(size 1.9939 1.9939)
					(thermal_gap 0.10795)
					(clearance 0.10795)
				)
			)
		)
		(pad "3" thru_hole circle
			(at -2.54 2.54 90)
			(size 1.9939 1.9939)
			(drill 0.249936)
			(layers "*.Cu" "*.Mask")
			(remove_unused_layers no)
			(net "T1_GND")
			(clearance 0.10795)
			(padstack
				(mode front_inner_back)
				(layer "Inner"
					(shape circle)
					(size 0.8001 0.8001)
					(clearance 0.1524)
				)
				(layer "B.Cu"
					(shape circle)
					(size 1.9939 1.9939)
					(thermal_gap 0.10795)
					(clearance 0.10795)
				)
			)
		)
		(pad "4" thru_hole circle
			(at 0 2.54 90)
			(size 1.0033 1.0033)
			(drill 0.249936)
			(layers "*.Cu" "*.Mask")
			(remove_unused_layers no)
			(net "TDR_DIFF_85_IN4_DP")
			(clearance 0.10795)
			(padstack
				(mode front_inner_back)
				(layer "Inner"
					(shape circle)
					(size 0.8001 0.8001)
					(clearance 0.1524)
				)
				(layer "B.Cu"
					(shape circle)
					(size 1.0033 1.0033)
					(thermal_gap 0.10795)
					(clearance 0.10795)
				)
			)
		)
	)
	(footprint ""
		(layer "B.Cu")
		(at 171.196 -112.232948)
		(property "Reference" "R166"
			(at 0 0 0)
			(layer "B.SilkS")
			(hide yes)
			(effects
				(font
					(size 1.27 1.27)
				)
				(justify mirror)
			)
		)
		(property "Value" ""
			(at 0 0 0)
			(layer "B.Fab")
			(effects
				(font
					(size 1.27 1.27)
				)
				(justify mirror)
			)
		)
		(duplicate_pad_numbers_are_jumpers no)
		(fp_line
			(start -0.7874 -0.4064)
			(end -0.7874 0.4064)
			(stroke
				(width 0.1524)
				(type default)
			)
			(layer "B.SilkS")
		)
		(fp_line
			(start -0.7874 0.4064)
			(end 0.7874 0.4064)
			(stroke
				(width 0.1524)
				(type default)
			)
			(layer "B.SilkS")
		)
		(fp_line
			(start 0.7874 -0.4064)
			(end -0.7874 -0.4064)
			(stroke
				(width 0.1524)
				(type default)
			)
			(layer "B.SilkS")
		)
		(fp_line
			(start 0.7874 0.4064)
			(end 0.7874 -0.4064)
			(stroke
				(width 0.1524)
				(type default)
			)
			(layer "B.SilkS")
		)
		(fp_line
			(start -0.67945 -0.3048)
			(end -0.67945 0.3048)
			(stroke
				(width 0.1)
				(type default)
			)
			(layer "B.Fab")
		)
		(fp_line
			(start -0.67945 0.3048)
			(end -0.120396 0.3048)
			(stroke
				(width 0.1)
				(type default)
			)
			(layer "B.Fab")
		)
		(fp_line
			(start -0.12065 -0.3048)
			(end -0.67945 -0.3048)
			(stroke
				(width 0.1)
				(type default)
			)
			(layer "B.Fab")
		)
		(fp_line
			(start -0.12065 -0.2794)
			(end -0.12065 -0.3048)
			(stroke
				(width 0.1)
				(type default)
			)
			(layer "B.Fab")
		)
		(fp_line
			(start -0.120396 0.2794)
			(end 0.12065 0.2794)
			(stroke
				(width 0.1)
				(type default)
			)
			(layer "B.Fab")
		)
		(fp_line
			(start -0.120396 0.3048)
			(end -0.120396 0.2794)
			(stroke
				(width 0.1)
				(type default)
			)
			(layer "B.Fab")
		)
		(fp_line
			(start 0.12065 -0.305054)
			(end 0.12065 -0.2794)
			(stroke
				(width 0.1)
				(type default)
			)
			(layer "B.Fab")
		)
		(fp_line
			(start 0.12065 -0.2794)
			(end -0.12065 -0.2794)
			(stroke
				(width 0.1)
				(type default)
			)
			(layer "B.Fab")
		)
		(fp_line
			(start 0.12065 0.2794)
			(end 0.12065 0.3048)
			(stroke
				(width 0.1)
				(type default)
			)
			(layer "B.Fab")
		)
		(fp_line
			(start 0.12065 0.3048)
			(end 0.67945 0.3048)
			(stroke
				(width 0.1)
				(type default)
			)
			(layer "B.Fab")
		)
		(fp_line
			(start 0.67945 -0.305054)
			(end 0.12065 -0.305054)
			(stroke
				(width 0.1)
				(type default)
			)
			(layer "B.Fab")
		)
		(fp_line
			(start 0.67945 0.3048)
			(end 0.67945 -0.305054)
			(stroke
				(width 0.1)
				(type default)
			)
			(layer "B.Fab")
		)
		(pad "1" smd circle
			(at 0.40005 0 180)
			(size 0 0)
			(layers "B.Cu" "B.Mask" "B.Paste")
			(net "FM_I3C_CPU0_MUX1_R_SEL")
		)
		(pad "2" smd circle
			(at -0.40005 0 180)
			(size 0 0)
			(layers "B.Cu" "B.Mask" "B.Paste")
			(net "FM_I3C_CPU0_MUX1_SEL")
		)
	)
	(footprint ""
		(layer "B.Cu")
		(at 53.151532 -421.180768)
		(property "Reference" "R3321"
			(at 0 0 0)
			(layer "B.SilkS")
			(hide yes)
			(effects
				(font
					(size 1.27 1.27)
				)
				(justify mirror)
			)
		)
		(property "Value" ""
			(at 0 0 0)
			(layer "B.Fab")
			(effects
				(font
					(size 1.27 1.27)
				)
				(justify mirror)
			)
		)
		(duplicate_pad_numbers_are_jumpers no)
		(fp_line
			(start -0.7874 -0.4064)
			(end -0.7874 0.4064)
			(stroke
				(width 0.1524)
				(type default)
			)
			(layer "B.SilkS")
		)
		(fp_line
			(start -0.7874 0.4064)
			(end 0.7874 0.4064)
			(stroke
				(width 0.1524)
				(type default)
			)
			(layer "B.SilkS")
		)
		(fp_line
			(start 0.7874 -0.4064)
			(end -0.7874 -0.4064)
			(stroke
				(width 0.1524)
				(type default)
			)
			(layer "B.SilkS")
		)
		(fp_line
			(start 0.7874 0.4064)
			(end 0.7874 -0.4064)
			(stroke
				(width 0.1524)
				(type default)
			)
			(layer "B.SilkS")
		)
		(fp_line
			(start -0.67945 -0.3048)
			(end -0.67945 0.3048)
			(stroke
				(width 0.1)
				(type default)
			)
			(layer "B.Fab")
		)
		(fp_line
			(start -0.67945 0.3048)
			(end -0.120396 0.3048)
			(stroke
				(width 0.1)
				(type default)
			)
			(layer "B.Fab")
		)
		(fp_line
			(start -0.12065 -0.3048)
			(end -0.67945 -0.3048)
			(stroke
				(width 0.1)
				(type default)
			)
			(layer "B.Fab")
		)
		(fp_line
			(start -0.12065 -0.2794)
			(end -0.12065 -0.3048)
			(stroke
				(width 0.1)
				(type default)
			)
			(layer "B.Fab")
		)
		(fp_line
			(start -0.120396 0.2794)
			(end 0.12065 0.2794)
			(stroke
				(width 0.1)
				(type default)
			)
			(layer "B.Fab")
		)
		(fp_line
			(start -0.120396 0.3048)
			(end -0.120396 0.2794)
			(stroke
				(width 0.1)
				(type default)
			)
			(layer "B.Fab")
		)
		(fp_line
			(start 0.12065 -0.305054)
			(end 0.12065 -0.2794)
			(stroke
				(width 0.1)
				(type default)
			)
			(layer "B.Fab")
		)
		(fp_line
			(start 0.12065 -0.2794)
			(end -0.12065 -0.2794)
			(stroke
				(width 0.1)
				(type default)
			)
			(layer "B.Fab")
		)
		(fp_line
			(start 0.12065 0.2794)
			(end 0.12065 0.3048)
			(stroke
				(width 0.1)
				(type default)
			)
			(layer "B.Fab")
		)
		(fp_line
			(start 0.12065 0.3048)
			(end 0.67945 0.3048)
			(stroke
				(width 0.1)
				(type default)
			)
			(layer "B.Fab")
		)
		(fp_line
			(start 0.67945 -0.305054)
			(end 0.12065 -0.305054)
			(stroke
				(width 0.1)
				(type default)
			)
			(layer "B.Fab")
		)
		(fp_line
			(start 0.67945 0.3048)
			(end 0.67945 -0.305054)
			(stroke
				(width 0.1)
				(type default)
			)
			(layer "B.Fab")
		)
		(pad "1" smd circle
			(at 0.40005 0 180)
			(size 0 0)
			(layers "B.Cu" "B.Mask" "B.Paste")
			(net "P3V3_AUX")
		)
		(pad "2" smd circle
			(at -0.40005 0 180)
			(size 0 0)
			(layers "B.Cu" "B.Mask" "B.Paste")
			(net "GPU_FPGA_READY_ISO")
		)
	)
)
